(kicad_pcb
	(version 20241229)
	(generator "pcbnew")
	(generator_version "9.0")
	(general
		(thickness 1.62)
		(legacy_teardrops no)
	)
	(paper "A4")
	(title_block
		(title "OCuLink to 10GbE adapter")
		(date "2026-02-23")
		(rev "1.1.0")
		(company "Antmicro Ltd")
		(comment 1 "www.antmicro.com")
		(comment 9 "footprints 479-484 of 510")
	)
	(layers
		(0 "F.Cu" signal)
		(4 "In1.Cu" signal)
		(6 "In2.Cu" signal)
		(8 "In3.Cu" signal)
		(10 "In4.Cu" signal)
		(12 "In5.Cu" signal)
		(14 "In6.Cu" signal)
		(2 "B.Cu" signal)
		(9 "F.Adhes" user "F.Adhesive")
		(11 "B.Adhes" user "B.Adhesive")
		(13 "F.Paste" user)
		(15 "B.Paste" user)
		(5 "F.SilkS" user "F.Silkscreen")
		(7 "B.SilkS" user "B.Silkscreen")
		(1 "F.Mask" user)
		(3 "B.Mask" user)
		(17 "Dwgs.User" user "User.Drawings")
		(19 "Cmts.User" user "User.Comments")
		(21 "Eco1.User" user "User.Eco1")
		(23 "Eco2.User" user "User.Eco2")
		(25 "Edge.Cuts" user)
		(27 "Margin" user)
		(31 "F.CrtYd" user "F.Courtyard")
		(29 "B.CrtYd" user "B.Courtyard")
		(35 "F.Fab" user)
		(33 "B.Fab" user)
	)
	(footprint "antmicro-footprints:R_0402_1005Metric"
		(layer "B.Cu")
		(at 102.08 90.164 180)
		(descr "Resistor SMD 0402")
		(tags "resistor SMD 0402")
		(property "Reference" "R123"
			(at -1.87 -2.736 0)
			(layer "B.SilkS")
			(effects
				(font
					(size 0.7 0.7)
					(thickness 0.15)
				)
				(justify left bottom mirror)
			)
		)
		(property "Value" "R_33R_0402"
			(at -1.011843 -1.772047 0)
			(layer "B.Fab")
			(hide yes)
			(effects
				(font
					(size 0.7 0.7)
					(thickness 0.15)
				)
				(justify left bottom mirror)
			)
		)
		(property "Datasheet" "https://www.bourns.com/docs/product-datasheets/cr.pdf"
			(at 0 0 0)
			(layer "B.Fab")
			(hide yes)
			(effects
				(font
					(size 1.27 1.27)
					(thickness 0.15)
				)
				(justify mirror)
			)
		)
		(property "Description" "SMD Chip Resistor, 33 ohm, ± 1%, 62.5 mW, 0402 [1005 Metric], Thick Film, General Purpose"
			(at 0 0 0)
			(layer "B.Fab")
			(hide yes)
			(effects
				(font
					(size 1.27 1.27)
					(thickness 0.15)
				)
				(justify mirror)
			)
		)
		(property "MPN" "CR0402-FX-33R0GLF"
			(at 0 0 0)
			(unlocked yes)
			(layer "B.Fab")
			(hide yes)
			(effects
				(font
					(size 1 1)
					(thickness 0.15)
				)
				(justify mirror)
			)
		)
		(property "Manufacturer" "Bourns"
			(at 0 0 0)
			(unlocked yes)
			(layer "B.Fab")
			(hide yes)
			(effects
				(font
					(size 1 1)
					(thickness 0.15)
				)
				(justify mirror)
			)
		)
		(property "License" "Apache-2.0"
			(at 0 0 0)
			(unlocked yes)
			(layer "B.Fab")
			(hide yes)
			(effects
				(font
					(size 1 1)
					(thickness 0.15)
				)
				(justify mirror)
			)
		)
		(property "Author" "Antmicro"
			(at 0 0 0)
			(unlocked yes)
			(layer "B.Fab")
			(hide yes)
			(effects
				(font
					(size 1 1)
					(thickness 0.15)
				)
				(justify mirror)
			)
		)
		(property "Val" "33R"
			(at 0 0 0)
			(unlocked yes)
			(layer "B.Fab")
			(hide yes)
			(effects
				(font
					(size 1 1)
					(thickness 0.15)
				)
				(justify mirror)
			)
		)
		(property "Tolerance" "1%"
			(at 0 0 0)
			(unlocked yes)
			(layer "B.Fab")
			(hide yes)
			(effects
				(font
					(size 1 1)
					(thickness 0.15)
				)
				(justify mirror)
			)
		)
		(sheetname "/X710-AT2 PCIe/")
		(sheetfile "x710-at2-pcie.kicad_sch")
		(attr smd exclude_from_pos_files exclude_from_bom dnp)
		(fp_rect
			(start -0.925 0.47)
			(end 0.925 -0.47)
			(stroke
				(width 0.05)
				(type default)
			)
			(fill no)
			(layer "B.CrtYd")
		)
		(fp_rect
			(start -0.5 0.25)
			(end 0.5 -0.25)
			(stroke
				(width 0.15)
				(type solid)
			)
			(fill no)
			(layer "B.Fab")
		)
		(pad "1" smd roundrect
			(at -0.48 0 180)
			(size 0.59 0.64)
			(layers "B.Cu" "B.Mask" "B.Paste")
			(roundrect_rratio 0.25)
			(net 407 "/X710-AT2 PCIe/GEN_CLK+")
			(pintype "passive")
		)
		(pad "2" smd roundrect
			(at 0.48 0 180)
			(size 0.59 0.64)
			(layers "B.Cu" "B.Mask" "B.Paste")
			(roundrect_rratio 0.25)
			(net 405 "/X710-AT2 PCIe/GEN_F_CLK+")
			(pintype "passive")
		)
	)
	(footprint "antmicro-footprints:C_0402_1005Metric"
		(layer "B.Cu")
		(at 88.225 94.6 90)
		(descr "Capacitor SMD 0402")
		(tags "capacitor SMD 0402")
		(property "Reference" "C97"
			(at 12.5 -0.462343 90)
			(layer "B.SilkS")
			(effects
				(font
					(size 0.7 0.7)
					(thickness 0.15)
				)
				(justify right top mirror)
			)
		)
		(property "Value" "C_1u_25V_0402"
			(at -1.022927 -2.155213 90)
			(layer "B.Fab")
			(hide yes)
			(effects
				(font
					(size 0.7 0.7)
					(thickness 0.15)
				)
				(justify right top mirror)
			)
		)
		(property "Datasheet" "https://www.murata.com/products/productdetail?partno=GRM155R61E105KE11%23"
			(at 0 0 90)
			(layer "B.Fab")
			(hide yes)
			(effects
				(font
					(size 1.27 1.27)
					(thickness 0.15)
				)
				(justify mirror)
			)
		)
		(property "Description" "SMD Multilayer Ceramic Capacitor, 1 µF, 25 V, 0402 [1005 Metric], ± 10%, X5R, GRM Series"
			(at 0 0 90)
			(layer "B.Fab")
			(hide yes)
			(effects
				(font
					(size 1.27 1.27)
					(thickness 0.15)
				)
				(justify mirror)
			)
		)
		(property "MPN" "GRM155R61E105KE11J"
			(at 0 0 90)
			(unlocked yes)
			(layer "B.Fab")
			(hide yes)
			(effects
				(font
					(size 1 1)
					(thickness 0.15)
				)
				(justify mirror)
			)
		)
		(property "Manufacturer" "Murata"
			(at 0 0 90)
			(unlocked yes)
			(layer "B.Fab")
			(hide yes)
			(effects
				(font
					(size 1 1)
					(thickness 0.15)
				)
				(justify mirror)
			)
		)
		(property "License" "Apache-2.0"
			(at 0 0 90)
			(unlocked yes)
			(layer "B.Fab")
			(hide yes)
			(effects
				(font
					(size 1 1)
					(thickness 0.15)
				)
				(justify mirror)
			)
		)
		(property "Author" "Antmicro"
			(at 0 0 90)
			(unlocked yes)
			(layer "B.Fab")
			(hide yes)
			(effects
				(font
					(size 1 1)
					(thickness 0.15)
				)
				(justify mirror)
			)
		)
		(property "Val" "1u"
			(at 0 0 90)
			(unlocked yes)
			(layer "B.Fab")
			(hide yes)
			(effects
				(font
					(size 1 1)
					(thickness 0.15)
				)
				(justify mirror)
			)
		)
		(property "Voltage" "25V"
			(at 0 0 90)
			(unlocked yes)
			(layer "B.Fab")
			(hide yes)
			(effects
				(font
					(size 1 1)
					(thickness 0.15)
				)
				(justify mirror)
			)
		)
		(property "Dielectric" "X5R"
			(at 0 0 90)
			(unlocked yes)
			(layer "B.Fab")
			(hide yes)
			(effects
				(font
					(size 1 1)
					(thickness 0.15)
				)
				(justify mirror)
			)
		)
		(sheetname "/X710-AT2 power/")
		(sheetfile "x710-at2-power.kicad_sch")
		(attr smd)
		(fp_rect
			(start -0.925 0.47)
			(end 0.925 -0.47)
			(stroke
				(width 0.05)
				(type default)
			)
			(fill no)
			(layer "B.CrtYd")
		)
		(fp_line
			(start 0.504 -0.248)
			(end -0.494 -0.248)
			(stroke
				(width 0.15)
				(type solid)
			)
			(layer "B.Fab")
		)
		(fp_line
			(start -0.494 -0.248)
			(end -0.494 0.25)
			(stroke
				(width 0.15)
				(type solid)
			)
			(layer "B.Fab")
		)
		(fp_line
			(start 0.504 0.25)
			(end 0.504 -0.248)
			(stroke
				(width 0.15)
				(type solid)
			)
			(layer "B.Fab")
		)
		(fp_line
			(start -0.494 0.25)
			(end 0.504 0.25)
			(stroke
				(width 0.15)
				(type solid)
			)
			(layer "B.Fab")
		)
		(pad "1" smd roundrect
			(at -0.48 0 90)
			(size 0.59 0.64)
			(layers "B.Cu" "B.Mask" "B.Paste")
			(roundrect_rratio 0.25)
			(net 28 "GND")
			(pintype "passive")
		)
		(pad "2" smd roundrect
			(at 0.48 0 90)
			(size 0.59 0.64)
			(layers "B.Cu" "B.Mask" "B.Paste")
			(roundrect_rratio 0.25)
			(net 1 "VCCA")
			(pintype "passive")
		)
	)
	(footprint "antmicro-footprints:C_0402_1005Metric"
		(layer "B.Cu")
		(at 73.1 106.65 180)
		(descr "Capacitor SMD 0402")
		(tags "capacitor SMD 0402")
		(property "Reference" "C188"
			(at 0.88 -0.35 0)
			(layer "B.SilkS")
			(effects
				(font
					(size 0.7 0.7)
					(thickness 0.15)
				)
				(justify left bottom mirror)
			)
		)
		(property "Value" "C_100n_0402"
			(at -1.022927 -2.155213 0)
			(layer "B.Fab")
			(hide yes)
			(effects
				(font
					(size 0.7 0.7)
					(thickness 0.15)
				)
				(justify left bottom mirror)
			)
		)
		(property "Datasheet" "https://www.murata.com/products/productdetail?partno=GRM155R61H104KE14%23"
			(at 0 0 0)
			(layer "B.Fab")
			(hide yes)
			(effects
				(font
					(size 1.27 1.27)
					(thickness 0.15)
				)
				(justify mirror)
			)
		)
		(property "Description" "SMD Multilayer Ceramic Capacitor, 0.1 µF, 50 V, 0402 [1005 Metric], ± 10%, X5R, GRM Series"
			(at 0 0 0)
			(layer "B.Fab")
			(hide yes)
			(effects
				(font
					(size 1.27 1.27)
					(thickness 0.15)
				)
				(justify mirror)
			)
		)
		(property "MPN" "GRM155R61H104KE14D"
			(at 0 0 180)
			(unlocked yes)
			(layer "B.Fab")
			(hide yes)
			(effects
				(font
					(size 1 1)
					(thickness 0.15)
				)
				(justify mirror)
			)
		)
		(property "Val" "100n"
			(at 0 0 180)
			(unlocked yes)
			(layer "B.Fab")
			(hide yes)
			(effects
				(font
					(size 1 1)
					(thickness 0.15)
				)
				(justify mirror)
			)
		)
		(property "Voltage" "50V"
			(at 0 0 180)
			(unlocked yes)
			(layer "B.Fab")
			(hide yes)
			(effects
				(font
					(size 1 1)
					(thickness 0.15)
				)
				(justify mirror)
			)
		)
		(property "Dielectric" "X5R"
			(at 0 0 180)
			(unlocked yes)
			(layer "B.Fab")
			(hide yes)
			(effects
				(font
					(size 1 1)
					(thickness 0.15)
				)
				(justify mirror)
			)
		)
		(property "Manufacturer" "Murata"
			(at 0 0 180)
			(unlocked yes)
			(layer "B.Fab")
			(hide yes)
			(effects
				(font
					(size 1 1)
					(thickness 0.15)
				)
				(justify mirror)
			)
		)
		(property "License" "Apache-2.0"
			(at 0 0 180)
			(unlocked yes)
			(layer "B.Fab")
			(hide yes)
			(effects
				(font
					(size 1 1)
					(thickness 0.15)
				)
				(justify mirror)
			)
		)
		(property "Author" "Antmicro"
			(at 0 0 180)
			(unlocked yes)
			(layer "B.Fab")
			(hide yes)
			(effects
				(font
					(size 1 1)
					(thickness 0.15)
				)
				(justify mirror)
			)
		)
		(sheetname "/X710-AT2 power/")
		(sheetfile "x710-at2-power.kicad_sch")
		(attr smd)
		(fp_rect
			(start -0.925 0.47)
			(end 0.925 -0.47)
			(stroke
				(width 0.05)
				(type default)
			)
			(fill no)
			(layer "B.CrtYd")
		)
		(fp_line
			(start 0.504 0.25)
			(end 0.504 -0.248)
			(stroke
				(width 0.15)
				(type solid)
			)
			(layer "B.Fab")
		)
		(fp_line
			(start 0.504 -0.248)
			(end -0.494 -0.248)
			(stroke
				(width 0.15)
				(type solid)
			)
			(layer "B.Fab")
		)
		(fp_line
			(start -0.494 0.25)
			(end 0.504 0.25)
			(stroke
				(width 0.15)
				(type solid)
			)
			(layer "B.Fab")
		)
		(fp_line
			(start -0.494 -0.248)
			(end -0.494 0.25)
			(stroke
				(width 0.15)
				(type solid)
			)
			(layer "B.Fab")
		)
		(pad "1" smd roundrect
			(at -0.48 0 180)
			(size 0.59 0.64)
			(layers "B.Cu" "B.Mask" "B.Paste")
			(roundrect_rratio 0.25)
			(net 28 "GND")
			(pintype "passive")
		)
		(pad "2" smd roundrect
			(at 0.48 0 180)
			(size 0.59 0.64)
			(layers "B.Cu" "B.Mask" "B.Paste")
			(roundrect_rratio 0.25)
			(net 302 "+1V0")
			(pintype "passive")
		)
	)
	(footprint "antmicro-footprints:USON-10_2.5x1mm_P0.5mm"
		(layer "B.Cu")
		(at 96.747999 55.88366 90)
		(descr "USON-10 2.5x1mm_ Pitch 0.5mm")
		(tags "USON-10 2.5x1mm Pitch 0.5mm")
		(property "Reference" "D7"
			(at -0.90134 -0.697999 0)
			(layer "B.SilkS")
			(effects
				(font
					(size 0.7 0.7)
					(thickness 0.15)
				)
				(justify right top mirror)
			)
		)
		(property "Value" "ESD204DQAR"
			(at 0.018 -2.499 90)
			(layer "B.Fab")
			(hide yes)
			(effects
				(font
					(size 0.7 0.7)
					(thickness 0.15)
				)
				(justify right top mirror)
			)
		)
		(property "Datasheet" "https://www.ti.com/lit/ds/symlink/esd204.pdf?ts=1706004844383&ref_url=https%253A%252F%252Fwww.ti.com%252Finterface%252Fdiodes%252Fesd-protection-diodes%252Fproducts.html"
			(at 0 0 90)
			(layer "B.Fab")
			(hide yes)
			(effects
				(font
					(size 1.27 1.27)
					(thickness 0.15)
				)
				(justify mirror)
			)
		)
		(property "Description" "TVS diode array, 30 kV, USON-10, 3.6 V, 0.55 pF"
			(at 0 0 90)
			(layer "B.Fab")
			(hide yes)
			(effects
				(font
					(size 1.27 1.27)
					(thickness 0.15)
				)
				(justify mirror)
			)
		)
		(property "MPN" "ESD204DQAR"
			(at 0 0 90)
			(unlocked yes)
			(layer "B.Fab")
			(hide yes)
			(effects
				(font
					(size 1 1)
					(thickness 0.15)
				)
				(justify mirror)
			)
		)
		(property "Manufacturer" "Texas Instruments"
			(at 0 0 90)
			(unlocked yes)
			(layer "B.Fab")
			(hide yes)
			(effects
				(font
					(size 1 1)
					(thickness 0.15)
				)
				(justify mirror)
			)
		)
		(property "Author" "Antmicro"
			(at 0 0 90)
			(unlocked yes)
			(layer "B.Fab")
			(hide yes)
			(effects
				(font
					(size 1 1)
					(thickness 0.15)
				)
				(justify mirror)
			)
		)
		(property "License" "Apache-2.0"
			(at 0 0 90)
			(unlocked yes)
			(layer "B.Fab")
			(hide yes)
			(effects
				(font
					(size 1 1)
					(thickness 0.15)
				)
				(justify mirror)
			)
		)
		(sheetname "/OCuLink/")
		(sheetfile "oculink.kicad_sch")
		(attr smd)
		(fp_line
			(start 0.498 -1.398)
			(end -0.5 -1.398)
			(stroke
				(width 0.15)
				(type solid)
			)
			(layer "B.SilkS")
		)
		(fp_line
			(start 0.498 1.401)
			(end -0.5 1.401)
			(stroke
				(width 0.15)
				(type solid)
			)
			(layer "B.SilkS")
		)
		(fp_circle
			(center -0.68 1.27)
			(end -0.63 1.27)
			(stroke
				(width 0.15)
				(type solid)
			)
			(fill yes)
			(layer "B.SilkS")
		)
		(fp_rect
			(start -0.8 1.5)
			(end 0.8 -1.499)
			(stroke
				(width 0.05)
				(type solid)
			)
			(fill no)
			(layer "B.CrtYd")
		)
		(fp_line
			(start -0.5 -1.249)
			(end 0.498 -1.249)
			(stroke
				(width 0.15)
				(type solid)
			)
			(layer "B.Fab")
		)
		(fp_line
			(start -0.5 1)
			(end -0.5 -1.249)
			(stroke
				(width 0.15)
				(type solid)
			)
			(layer "B.Fab")
		)
		(fp_line
			(start 0.498 1.25)
			(end 0.498 -1.249)
			(stroke
				(width 0.15)
				(type solid)
			)
			(layer "B.Fab")
		)
		(fp_line
			(start 0.498 1.25)
			(end -0.25 1.25)
			(stroke
				(width 0.15)
				(type solid)
			)
			(layer "B.Fab")
		)
		(fp_line
			(start -0.25 1.25)
			(end -0.5 1)
			(stroke
				(width 0.15)
				(type solid)
			)
			(layer "B.Fab")
		)
		(pad "1" smd roundrect
			(at -0.387 1 180)
			(size 0.25 0.55)
			(layers "B.Cu" "B.Mask" "B.Paste")
			(roundrect_rratio 0.25)
			(net 80 "/OCuLink/PCIe_{x4}.RX2+")
			(pintype "passive")
		)
		(pad "2" smd roundrect
			(at -0.387 0.5 180)
			(size 0.25 0.55)
			(layers "B.Cu" "B.Mask" "B.Paste")
			(roundrect_rratio 0.25)
			(net 104 "/OCuLink/PCIe_{x4}.RX2-")
			(pintype "passive")
		)
		(pad "3" smd roundrect
			(at -0.387 0 180)
			(size 0.4 0.55)
			(layers "B.Cu" "B.Mask" "B.Paste")
			(roundrect_rratio 0.25)
			(net 28 "GND")
			(pintype "power_in")
		)
		(pad "4" smd roundrect
			(at -0.387 -0.498 180)
			(size 0.25 0.55)
			(layers "B.Cu" "B.Mask" "B.Paste")
			(roundrect_rratio 0.25)
			(net 98 "/OCuLink/PCIe_{x4}.RX3+")
			(pintype "passive")
		)
		(pad "5" smd roundrect
			(at -0.387 -0.998 180)
			(size 0.25 0.55)
			(layers "B.Cu" "B.Mask" "B.Paste")
			(roundrect_rratio 0.25)
			(net 109 "/OCuLink/PCIe_{x4}.RX3-")
			(pintype "passive")
		)
		(pad "6" smd roundrect
			(at 0.385 -0.998 180)
			(size 0.25 0.55)
			(layers "B.Cu" "B.Mask" "B.Paste")
			(roundrect_rratio 0.25)
			(net 109 "/OCuLink/PCIe_{x4}.RX3-")
			(pintype "passive")
		)
		(pad "7" smd roundrect
			(at 0.385 -0.498 180)
			(size 0.25 0.55)
			(layers "B.Cu" "B.Mask" "B.Paste")
			(roundrect_rratio 0.25)
			(net 98 "/OCuLink/PCIe_{x4}.RX3+")
			(pintype "passive")
		)
		(pad "8" smd roundrect
			(at 0.385 0 180)
			(size 0.4 0.55)
			(layers "B.Cu" "B.Mask" "B.Paste")
			(roundrect_rratio 0.25)
			(net 28 "GND")
			(pintype "passive")
		)
		(pad "9" smd roundrect
			(at 0.385 0.5 180)
			(size 0.25 0.55)
			(layers "B.Cu" "B.Mask" "B.Paste")
			(roundrect_rratio 0.25)
			(net 104 "/OCuLink/PCIe_{x4}.RX2-")
			(pintype "passive")
		)
		(pad "10" smd roundrect
			(at 0.385 1 180)
			(size 0.25 0.55)
			(layers "B.Cu" "B.Mask" "B.Paste")
			(roundrect_rratio 0.25)
			(net 80 "/OCuLink/PCIe_{x4}.RX2+")
			(pintype "passive")
		)
	)
	(footprint "antmicro-footprints:TP_SMD_0.75mm"
		(layer "B.Cu")
		(at 61.299999 91.850001 180)
		(property "Reference" "TP41"
			(at 0 0.6 0)
			(layer "B.SilkS")
			(hide yes)
			(effects
				(font
					(size 0.7 0.7)
					(thickness 0.15)
				)
				(justify left bottom mirror)
			)
		)
		(property "Value" "TP_0.75mm_SMD"
			(at 0 -1.2 0)
			(layer "B.Fab")
			(hide yes)
			(effects
				(font
					(size 0.7 0.7)
					(thickness 0.15)
				)
				(justify left bottom mirror)
			)
		)
		(property "Description" "SMT test point"
			(at 0 0 0)
			(layer "B.Fab")
			(hide yes)
			(effects
				(font
					(size 1.27 1.27)
					(thickness 0.15)
				)
				(justify mirror)
			)
		)
		(property "MPN" ""
			(at 0 0 0)
			(unlocked yes)
			(layer "B.Fab")
			(hide yes)
			(effects
				(font
					(size 1 1)
					(thickness 0.15)
				)
				(justify mirror)
			)
		)
		(property "Manufacturer" ""
			(at 0 0 0)
			(unlocked yes)
			(layer "B.Fab")
			(hide yes)
			(effects
				(font
					(size 1 1)
					(thickness 0.15)
				)
				(justify mirror)
			)
		)
		(property "Author" "Antmicro"
			(at 0 0 0)
			(unlocked yes)
			(layer "B.Fab")
			(hide yes)
			(effects
				(font
					(size 1 1)
					(thickness 0.15)
				)
				(justify mirror)
			)
		)
		(property "License" "Apache-2.0"
			(at 0 0 0)
			(unlocked yes)
			(layer "B.Fab")
			(hide yes)
			(effects
				(font
					(size 1 1)
					(thickness 0.15)
				)
				(justify mirror)
			)
		)
		(sheetname "/Power/")
		(sheetfile "power.kicad_sch")
		(attr exclude_from_pos_files exclude_from_bom)
		(fp_circle
			(center 0 0)
			(end 0.475 0)
			(stroke
				(width 0.05)
				(type default)
			)
			(fill no)
			(layer "B.CrtYd")
		)
		(pad "1" smd circle
			(at 0 0 180)
			(size 0.75 0.75)
			(layers "B.Cu" "B.Mask")
			(net 311 "/Power/+DVDD_OUT")
			(pinfunction "1")
			(pintype "passive")
		)
	)
	(footprint "antmicro-footprints:TP_SMD_0.75mm"
		(layer "B.Cu")
		(at 61.304999 107.255001 180)
		(property "Reference" "TP40"
			(at 0 0.6 0)
			(layer "B.SilkS")
			(hide yes)
			(effects
				(font
					(size 0.7 0.7)
					(thickness 0.15)
				)
				(justify left bottom mirror)
			)
		)
		(property "Value" "TP_0.75mm_SMD"
			(at 0 -1.2 0)
			(layer "B.Fab")
			(hide yes)
			(effects
				(font
					(size 0.7 0.7)
					(thickness 0.15)
				)
				(justify left bottom mirror)
			)
		)
		(property "Description" "SMT test point"
			(at 0 0 0)
			(layer "B.Fab")
			(hide yes)
			(effects
				(font
					(size 1.27 1.27)
					(thickness 0.15)
				)
				(justify mirror)
			)
		)
		(property "MPN" ""
			(at 0 0 0)
			(unlocked yes)
			(layer "B.Fab")
			(hide yes)
			(effects
				(font
					(size 1 1)
					(thickness 0.15)
				)
				(justify mirror)
			)
		)
		(property "Manufacturer" ""
			(at 0 0 0)
			(unlocked yes)
			(layer "B.Fab")
			(hide yes)
			(effects
				(font
					(size 1 1)
					(thickness 0.15)
				)
				(justify mirror)
			)
		)
		(property "Author" "Antmicro"
			(at 0 0 0)
			(unlocked yes)
			(layer "B.Fab")
			(hide yes)
			(effects
				(font
					(size 1 1)
					(thickness 0.15)
				)
				(justify mirror)
			)
		)
		(property "License" "Apache-2.0"
			(at 0 0 0)
			(unlocked yes)
			(layer "B.Fab")
			(hide yes)
			(effects
				(font
					(size 1 1)
					(thickness 0.15)
				)
				(justify mirror)
			)
		)
		(sheetname "/Power/")
		(sheetfile "power.kicad_sch")
		(attr exclude_from_pos_files exclude_from_bom)
		(fp_circle
			(center 0 0)
			(end 0.475 0)
			(stroke
				(width 0.05)
				(type default)
			)
			(fill no)
			(layer "B.CrtYd")
		)
		(pad "1" smd circle
			(at 0 0 180)
			(size 0.75 0.75)
			(layers "B.Cu" "B.Mask")
			(net 312 "/Power/+1V0_OUT")
			(pinfunction "1")
			(pintype "passive")
		)
	)
)
